# S9S_MB_2U (Grand Teton) — schematic netlist excerpt (pin names and nets, part order shuffled) for the footprints in the layout excerpt that follows; sources: Cadence DE-HDL packaged netlist, KiCad conversion of 03242023_DA0F0TMBIJ0_F0T_Motherboard_J_brd_V01_OCP.brd

PC1193  Q_CAP  1UF 16V 10% X6S  pkg C0402  page 292 : A = PVCCINFAON_CPU1_VREF ; B = GND
PR3339  Q_RES  0 5% CHIP  pkg 0402LF  page 282 : A = P3V3_AUX ; B = PVNN_MAIN_CPU0_VCC

(kicad_pcb
	(version 20260206)
	(generator "pcbnew")
	(generator_version "10.0")
	(general
		(thickness 1.6)
		(legacy_teardrops no)
	)
	(paper "A4")
	(title_block
		(title "03242023_DA0F0TMBIJ0_F0T_Motherboard_J_brd_V01_OCP.brd")
		(comment 1 "Grand Teton / footprints 2693-2694 of 6105")
	)
	(layers
		(0 "F.Cu" signal "TOP")
		(4 "In1.Cu" signal "GND")
		(6 "In2.Cu" signal "IN1")
		(8 "In3.Cu" signal "GND1")
		(10 "In4.Cu" signal "IN2")
		(12 "In5.Cu" signal "GND2")
		(14 "In6.Cu" signal "IN3")
		(16 "In7.Cu" signal "GND3")
		(18 "In8.Cu" signal "VCC")
		(20 "In9.Cu" signal "VCC1")
		(22 "In10.Cu" signal "GND4")
		(24 "In11.Cu" signal "IN4")
		(26 "In12.Cu" signal "GND5")
		(28 "In13.Cu" signal "IN5")
		(30 "In14.Cu" signal "GND6")
		(32 "In15.Cu" signal "IN6")
		(34 "In16.Cu" signal "GND7")
		(2 "B.Cu" signal "BOTTOM")
		(9 "F.Adhes" user "F.Adhesive")
		(11 "B.Adhes" user "B.Adhesive")
		(13 "F.Paste" user "Package Geometry/Pastemask Top")
		(15 "B.Paste" user "Package Geometry/Pastemask Bottom")
		(5 "F.SilkS" user "Ref Des/Silkscreen Top")
		(7 "B.SilkS" user "Ref Des/Silkscreen Bottom")
		(1 "F.Mask" user "Board Geometry/Soldermask Top")
		(3 "B.Mask" user "Board Geometry/Soldermask Bottom")
		(17 "Dwgs.User" user "User.Drawings")
		(19 "Cmts.User" user "User.Comments")
		(21 "Eco1.User" user "User.Eco1")
		(23 "Eco2.User" user "User.Eco2")
		(25 "Edge.Cuts" user "Board Geometry/Outline")
		(27 "Margin" user)
		(31 "F.CrtYd" user "Package Geometry/Place Bound Top")
		(29 "B.CrtYd" user "Package Geometry/Place Bound Bottom")
		(35 "F.Fab" user "Ref Des/Assembly Top")
		(33 "B.Fab" user "Ref Des/Assembly Bottom")
	)
	(footprint ""
		(layer "F.Cu")
		(at 432.67884 -184.544208)
		(property "Reference" "PR3339"
			(at 0 0 0)
			(layer "F.SilkS")
			(hide yes)
			(effects
				(font
					(size 1.27 1.27)
				)
			)
		)
		(property "Value" ""
			(at 0 0 0)
			(layer "F.Fab")
			(effects
				(font
					(size 1.27 1.27)
				)
			)
		)
		(duplicate_pad_numbers_are_jumpers no)
		(fp_line
			(start -0.7874 -0.4064)
			(end 0.7874 -0.4064)
			(stroke
				(width 0.1524)
				(type default)
			)
			(layer "F.SilkS")
		)
		(fp_line
			(start -0.7874 0.4064)
			(end -0.7874 -0.4064)
			(stroke
				(width 0.1524)
				(type default)
			)
			(layer "F.SilkS")
		)
		(fp_line
			(start 0.7874 -0.4064)
			(end 0.7874 0.4064)
			(stroke
				(width 0.1524)
				(type default)
			)
			(layer "F.SilkS")
		)
		(fp_line
			(start 0.7874 0.4064)
			(end -0.7874 0.4064)
			(stroke
				(width 0.1524)
				(type default)
			)
			(layer "F.SilkS")
		)
		(fp_line
			(start -0.67945 -0.305054)
			(end -0.12065 -0.305054)
			(stroke
				(width 0.1)
				(type default)
			)
			(layer "F.Fab")
		)
		(fp_line
			(start -0.67945 0.3048)
			(end -0.67945 -0.305054)
			(stroke
				(width 0.1)
				(type default)
			)
			(layer "F.Fab")
		)
		(fp_line
			(start -0.12065 -0.305054)
			(end -0.12065 -0.2794)
			(stroke
				(width 0.1)
				(type default)
			)
			(layer "F.Fab")
		)
		(fp_line
			(start -0.12065 -0.2794)
			(end 0.12065 -0.2794)
			(stroke
				(width 0.1)
				(type default)
			)
			(layer "F.Fab")
		)
		(fp_line
			(start -0.12065 0.2794)
			(end -0.12065 0.3048)
			(stroke
				(width 0.1)
				(type default)
			)
			(layer "F.Fab")
		)
		(fp_line
			(start -0.12065 0.3048)
			(end -0.67945 0.3048)
			(stroke
				(width 0.1)
				(type default)
			)
			(layer "F.Fab")
		)
		(fp_line
			(start 0.120396 0.2794)
			(end -0.12065 0.2794)
			(stroke
				(width 0.1)
				(type default)
			)
			(layer "F.Fab")
		)
		(fp_line
			(start 0.120396 0.3048)
			(end 0.120396 0.2794)
			(stroke
				(width 0.1)
				(type default)
			)
			(layer "F.Fab")
		)
		(fp_line
			(start 0.12065 -0.3048)
			(end 0.67945 -0.3048)
			(stroke
				(width 0.1)
				(type default)
			)
			(layer "F.Fab")
		)
		(fp_line
			(start 0.12065 -0.2794)
			(end 0.12065 -0.3048)
			(stroke
				(width 0.1)
				(type default)
			)
			(layer "F.Fab")
		)
		(fp_line
			(start 0.67945 -0.3048)
			(end 0.67945 0.3048)
			(stroke
				(width 0.1)
				(type default)
			)
			(layer "F.Fab")
		)
		(fp_line
			(start 0.67945 0.3048)
			(end 0.120396 0.3048)
			(stroke
				(width 0.1)
				(type default)
			)
			(layer "F.Fab")
		)
		(pad "1" smd circle
			(at -0.40005 0)
			(size 0 0)
			(layers "F.Cu" "F.Mask" "F.Paste")
			(net "P3V3_AUX")
		)
		(pad "2" smd circle
			(at 0.40005 0)
			(size 0 0)
			(layers "F.Cu" "F.Mask" "F.Paste")
			(net "PVNN_MAIN_CPU0_VCC")
		)
	)
	(footprint ""
		(layer "F.Cu")
		(at 28.853638 -125.194314 -90)
		(property "Reference" "PC1193"
			(at 0 0 270)
			(layer "F.SilkS")
			(hide yes)
			(effects
				(font
					(size 1.27 1.27)
				)
			)
		)
		(property "Value" ""
			(at 0 0 270)
			(layer "F.Fab")
			(effects
				(font
					(size 1.27 1.27)
				)
			)
		)
		(duplicate_pad_numbers_are_jumpers no)
		(fp_line
			(start -0.7874 0.4064)
			(end -0.7874 -0.4064)
			(stroke
				(width 0.1524)
				(type default)
			)
			(layer "F.SilkS")
		)
		(fp_line
			(start 0.7874 0.4064)
			(end -0.7874 0.4064)
			(stroke
				(width 0.1524)
				(type default)
			)
			(layer "F.SilkS")
		)
		(fp_line
			(start -0.7874 -0.4064)
			(end 0.7874 -0.4064)
			(stroke
				(width 0.1524)
				(type default)
			)
			(layer "F.SilkS")
		)
		(fp_line
			(start 0.7874 -0.4064)
			(end 0.7874 0.4064)
			(stroke
				(width 0.1524)
				(type default)
			)
			(layer "F.SilkS")
		)
		(fp_line
			(start -0.67945 0.3048)
			(end -0.67945 -0.305054)
			(stroke
				(width 0.1)
				(type default)
			)
			(layer "F.Fab")
		)
		(fp_line
			(start -0.12065 0.3048)
			(end -0.67945 0.3048)
			(stroke
				(width 0.1)
				(type default)
			)
			(layer "F.Fab")
		)
		(fp_line
			(start 0.120396 0.3048)
			(end 0.120396 0.2794)
			(stroke
				(width 0.1)
				(type default)
			)
			(layer "F.Fab")
		)
		(fp_line
			(start 0.67945 0.3048)
			(end 0.120396 0.3048)
			(stroke
				(width 0.1)
				(type default)
			)
			(layer "F.Fab")
		)
		(fp_line
			(start -0.12065 0.2794)
			(end -0.12065 0.3048)
			(stroke
				(width 0.1)
				(type default)
			)
			(layer "F.Fab")
		)
		(fp_line
			(start 0.120396 0.2794)
			(end -0.12065 0.2794)
			(stroke
				(width 0.1)
				(type default)
			)
			(layer "F.Fab")
		)
		(fp_line
			(start -0.12065 -0.2794)
			(end 0.12065 -0.2794)
			(stroke
				(width 0.1)
				(type default)
			)
			(layer "F.Fab")
		)
		(fp_line
			(start 0.12065 -0.2794)
			(end 0.12065 -0.3048)
			(stroke
				(width 0.1)
				(type default)
			)
			(layer "F.Fab")
		)
		(fp_line
			(start 0.12065 -0.3048)
			(end 0.67945 -0.3048)
			(stroke
				(width 0.1)
				(type default)
			)
			(layer "F.Fab")
		)
		(fp_line
			(start 0.67945 -0.3048)
			(end 0.67945 0.3048)
			(stroke
				(width 0.1)
				(type default)
			)
			(layer "F.Fab")
		)
		(fp_line
			(start -0.67945 -0.305054)
			(end -0.12065 -0.305054)
			(stroke
				(width 0.1)
				(type default)
			)
			(layer "F.Fab")
		)
		(fp_line
			(start -0.12065 -0.305054)
			(end -0.12065 -0.2794)
			(stroke
				(width 0.1)
				(type default)
			)
			(layer "F.Fab")
		)
		(pad "1" smd circle
			(at -0.40005 0 270)
			(size 0 0)
			(layers "F.Cu" "F.Mask" "F.Paste")
			(net "PVCCINFAON_CPU1_VREF")
		)
		(pad "2" smd circle
			(at 0.40005 0 270)
			(size 0 0)
			(layers "F.Cu" "F.Mask" "F.Paste")
			(net "GND")
		)
	)
)
